(kicad_pcb
	(version 20241229)
	(generator "pcbnew")
	(generator_version "9.0")
	(general
		(thickness 1.294)
		(legacy_teardrops no)
	)
	(paper "A3")
	(title_block
		(title "Kintex 410T devboard")
		(date "2024-04-03")
		(rev "1.1.2")
		(comment 9 "footprint 89 of 975 (J18), pads 93-182 of 564")
	)
	(layers
		(0 "F.Cu" mixed)
		(4 "In1.Cu" power)
		(6 "In2.Cu" power)
		(8 "In3.Cu" mixed)
		(10 "In4.Cu" power)
		(12 "In5.Cu" mixed)
		(14 "In6.Cu" power)
		(16 "In7.Cu" mixed)
		(18 "In8.Cu" power)
		(2 "B.Cu" mixed)
		(9 "F.Adhes" user "F.Adhesive")
		(11 "B.Adhes" user "B.Adhesive")
		(13 "F.Paste" user)
		(15 "B.Paste" user)
		(5 "F.SilkS" user "F.Silkscreen")
		(7 "B.SilkS" user "B.Silkscreen")
		(1 "F.Mask" user)
		(3 "B.Mask" user)
		(17 "Dwgs.User" user "User.Drawings")
		(19 "Cmts.User" user "User.Comments")
		(21 "Eco1.User" user "User.Eco1")
		(23 "Eco2.User" user "User.Eco2")
		(25 "Edge.Cuts" user)
		(27 "Margin" user)
		(31 "F.CrtYd" user "F.Courtyard")
		(29 "B.CrtYd" user "B.Courtyard")
		(35 "F.Fab" user)
		(33 "B.Fab" user)
	)
	(footprint "antmicro-footprints:ASP-184329-01_mounting_holes"
		(layer "F.Cu")
		(at 162.000001 106.000001 90)
		(property "Reference" "J18"
			(at 28.280001 4.299999 180)
			(layer "F.SilkS")
			(effects
				(font
					(size 0.7 0.7)
					(thickness 0.15)
				)
				(justify left bottom)
			)
		)
		(property "Value" "ASP-184329-01_mounting_holes"
			(at -8.4 0.2 90)
			(layer "F.Fab")
			(effects
				(font
					(size 0.7 0.7)
					(thickness 0.15)
				)
				(justify left bottom)
			)
		)
		(property "Description" "Mezzanine Connector, Array, Female, 1.27 mm, 14 Rows, 560 Contacts, Surface Mount"
			(at 0 0 90)
			(layer "F.Fab")
			(hide yes)
			(effects
				(font
					(size 1.27 1.27)
					(thickness 0.15)
				)
			)
		)
		(property "Author" "Antmicro"
			(at 268.000002 -56 0)
			(layer "F.Fab")
			(hide yes)
			(effects
				(font
					(size 1 1)
					(thickness 0.15)
				)
			)
		)
		(property "License" "Apache-2.0"
			(at 268.000002 -56 0)
			(layer "F.Fab")
			(hide yes)
			(effects
				(font
					(size 1 1)
					(thickness 0.15)
				)
			)
		)
		(property "MPN" "ASP-184329-01"
			(at 268.000002 -56 0)
			(layer "F.Fab")
			(hide yes)
			(effects
				(font
					(size 1 1)
					(thickness 0.15)
				)
			)
		)
		(property "Manufacturer" "Samtec"
			(at 268.000002 -56 0)
			(layer "F.Fab")
			(hide yes)
			(effects
				(font
					(size 1 1)
					(thickness 0.15)
				)
			)
		)
		(sheetname "FMC+ HSPC")
		(sheetfile "fmc-hspc.kicad_sch")
		(attr smd)
		(pad "C09" smd circle
			(at 14.605 3.173 90)
			(size 0.64 0.64)
			(layers "F.Cu" "F.Mask")
			(net 1 "GND")
			(pinfunction "GND")
			(pintype "passive")
		)
		(pad "C10" smd circle
			(at 13.335 3.173 90)
			(size 0.64 0.64)
			(layers "F.Cu" "F.Mask")
			(net 72 "unconnected-(J18C-LA06_P-PadC10)")
			(pinfunction "LA06_P")
			(pintype "passive+no_connect")
		)
		(pad "C11" smd circle
			(at 12.063 3.173 90)
			(size 0.64 0.64)
			(layers "F.Cu" "F.Mask")
			(net 77 "unconnected-(J18C-LA06_N-PadC11)")
			(pinfunction "LA06_N")
			(pintype "passive+no_connect")
		)
		(pad "C12" smd circle
			(at 10.794 3.173 90)
			(size 0.64 0.64)
			(layers "F.Cu" "F.Mask")
			(net 1 "GND")
			(pinfunction "GND")
			(pintype "passive")
		)
		(pad "C13" smd circle
			(at 9.525 3.173 90)
			(size 0.64 0.64)
			(layers "F.Cu" "F.Mask")
			(net 1 "GND")
			(pinfunction "GND")
			(pintype "passive")
		)
		(pad "C14" smd circle
			(at 8.255 3.173 90)
			(size 0.64 0.64)
			(layers "F.Cu" "F.Mask")
			(net 84 "unconnected-(J18C-LA10_P-PadC14)")
			(pinfunction "LA10_P")
			(pintype "passive+no_connect")
		)
		(pad "C15" smd circle
			(at 6.985 3.173 90)
			(size 0.64 0.64)
			(layers "F.Cu" "F.Mask")
			(net 85 "unconnected-(J18C-LA10_N-PadC15)")
			(pinfunction "LA10_N")
			(pintype "passive+no_connect")
		)
		(pad "C16" smd circle
			(at 5.714 3.173 90)
			(size 0.64 0.64)
			(layers "F.Cu" "F.Mask")
			(net 1 "GND")
			(pinfunction "GND")
			(pintype "passive")
		)
		(pad "C17" smd circle
			(at 4.445 3.173 90)
			(size 0.64 0.64)
			(layers "F.Cu" "F.Mask")
			(net 1 "GND")
			(pinfunction "GND")
			(pintype "passive")
		)
		(pad "C18" smd circle
			(at 3.173 3.173 90)
			(size 0.64 0.64)
			(layers "F.Cu" "F.Mask")
			(net 86 "unconnected-(J18C-LA14_P-PadC18)")
			(pinfunction "LA14_P")
			(pintype "passive+no_connect")
		)
		(pad "C19" smd circle
			(at 1.904 3.173 90)
			(size 0.64 0.64)
			(layers "F.Cu" "F.Mask")
			(net 90 "unconnected-(J18C-LA14_N-PadC19)")
			(pinfunction "LA14_N")
			(pintype "passive+no_connect")
		)
		(pad "C20" smd circle
			(at 0.633 3.173 90)
			(size 0.64 0.64)
			(layers "F.Cu" "F.Mask")
			(net 1 "GND")
			(pinfunction "GND")
			(pintype "passive")
		)
		(pad "C21" smd circle
			(at -0.635 3.173 90)
			(size 0.64 0.64)
			(layers "F.Cu" "F.Mask")
			(net 1 "GND")
			(pinfunction "GND")
			(pintype "passive")
		)
		(pad "C22" smd circle
			(at -1.905 3.173 90)
			(size 0.64 0.64)
			(layers "F.Cu" "F.Mask")
			(net 91 "unconnected-(J18C-LA18_P_CC-PadC22)")
			(pinfunction "LA18_P_CC")
			(pintype "passive+no_connect")
		)
		(pad "C23" smd circle
			(at -3.176 3.173 90)
			(size 0.64 0.64)
			(layers "F.Cu" "F.Mask")
			(net 92 "unconnected-(J18C-LA18_N_CC-PadC23)")
			(pinfunction "LA18_N_CC")
			(pintype "passive+no_connect")
		)
		(pad "C24" smd circle
			(at -4.446 3.173 90)
			(size 0.64 0.64)
			(layers "F.Cu" "F.Mask")
			(net 1 "GND")
			(pinfunction "GND")
			(pintype "passive")
		)
		(pad "C25" smd circle
			(at -5.715 3.173 90)
			(size 0.64 0.64)
			(layers "F.Cu" "F.Mask")
			(net 1 "GND")
			(pinfunction "GND")
			(pintype "passive")
		)
		(pad "C26" smd circle
			(at -6.986 3.173 90)
			(size 0.64 0.64)
			(layers "F.Cu" "F.Mask")
			(net 93 "unconnected-(J18C-LA27_P-PadC26)")
			(pinfunction "LA27_P")
			(pintype "passive+no_connect")
		)
		(pad "C27" smd circle
			(at -8.257 3.173 90)
			(size 0.64 0.64)
			(layers "F.Cu" "F.Mask")
			(net 94 "unconnected-(J18C-LA27_N-PadC27)")
			(pinfunction "LA27_N")
			(pintype "passive+no_connect")
		)
		(pad "C28" smd circle
			(at -9.526 3.173 90)
			(size 0.64 0.64)
			(layers "F.Cu" "F.Mask")
			(net 1 "GND")
			(pinfunction "GND")
			(pintype "passive")
		)
		(pad "C29" smd circle
			(at -10.795 3.173 90)
			(size 0.64 0.64)
			(layers "F.Cu" "F.Mask")
			(net 1 "GND")
			(pinfunction "GND")
			(pintype "passive")
		)
		(pad "C30" smd circle
			(at -12.065 3.173 90)
			(size 0.64 0.64)
			(layers "F.Cu" "F.Mask")
			(net 383 "FMC.SCL_3V3")
			(pinfunction "SCL")
			(pintype "passive")
		)
		(pad "C31" smd circle
			(at -13.337 3.173 90)
			(size 0.64 0.64)
			(layers "F.Cu" "F.Mask")
			(net 380 "FMC.SDA_3V3")
			(pinfunction "SDA")
			(pintype "passive")
		)
		(pad "C32" smd circle
			(at -14.606 3.173 90)
			(size 0.64 0.64)
			(layers "F.Cu" "F.Mask")
			(net 1 "GND")
			(pinfunction "GND")
			(pintype "passive")
		)
		(pad "C33" smd circle
			(at -15.875 3.173 90)
			(size 0.64 0.64)
			(layers "F.Cu" "F.Mask")
			(net 1 "GND")
			(pinfunction "GND")
			(pintype "passive")
		)
		(pad "C34" smd circle
			(at -17.145 3.173 90)
			(size 0.64 0.64)
			(layers "F.Cu" "F.Mask")
			(net 95 "unconnected-(J18B-GA0-PadC34)")
			(pinfunction "GA0")
			(pintype "passive+no_connect")
		)
		(pad "C35" smd circle
			(at -18.415 3.173 90)
			(size 0.64 0.64)
			(layers "F.Cu" "F.Mask")
			(net 59 "12P0V")
			(pinfunction "12P0V")
			(pintype "passive")
		)
		(pad "C36" smd circle
			(at -19.685 3.173 90)
			(size 0.64 0.64)
			(layers "F.Cu" "F.Mask")
			(net 1 "GND")
			(pinfunction "GND")
			(pintype "passive")
		)
		(pad "C37" smd circle
			(at -20.956 3.173 90)
			(size 0.64 0.64)
			(layers "F.Cu" "F.Mask")
			(net 59 "12P0V")
			(pinfunction "12P0V")
			(pintype "passive")
		)
		(pad "C38" smd circle
			(at -22.226 3.173 90)
			(size 0.64 0.64)
			(layers "F.Cu" "F.Mask")
			(net 1 "GND")
			(pinfunction "GND")
			(pintype "passive")
		)
		(pad "C39" smd circle
			(at -23.497 3.173 90)
			(size 0.64 0.64)
			(layers "F.Cu" "F.Mask")
			(net 24 "+3V3")
			(pinfunction "3P3V")
			(pintype "passive")
		)
		(pad "C40" smd circle
			(at -24.767 3.173 90)
			(size 0.64 0.64)
			(layers "F.Cu" "F.Mask")
			(net 1 "GND")
			(pinfunction "GND")
			(pintype "passive")
		)
		(pad "D01" smd circle
			(at 24.765 1.904 90)
			(size 0.64 0.64)
			(layers "F.Cu" "F.Mask")
			(net 99 "Net-(J18B-PG_C2M)")
			(pinfunction "PG_C2M")
			(pintype "passive")
		)
		(pad "D02" smd circle
			(at 23.495 1.904 90)
			(size 0.64 0.64)
			(layers "F.Cu" "F.Mask")
			(net 1 "GND")
			(pinfunction "GND")
			(pintype "passive")
		)
		(pad "D03" smd circle
			(at 22.225 1.904 90)
			(size 0.64 0.64)
			(layers "F.Cu" "F.Mask")
			(net 1 "GND")
			(pinfunction "GND")
			(pintype "passive")
		)
		(pad "D04" smd circle
			(at 20.954 1.904 90)
			(size 0.64 0.64)
			(layers "F.Cu" "F.Mask")
			(net 627 "/FMC+ HSPC/GTR_REFCLK0_R_P")
			(pinfunction "GBTCLK0_M2C_P")
			(pintype "passive")
		)
		(pad "D05" smd circle
			(at 19.684 1.904 90)
			(size 0.64 0.64)
			(layers "F.Cu" "F.Mask")
			(net 629 "/FMC+ HSPC/GTR_REFCLK0_R_N")
			(pinfunction "GBTCLK0_M2C_N")
			(pintype "passive")
		)
		(pad "D06" smd circle
			(at 18.414 1.904 90)
			(size 0.64 0.64)
			(layers "F.Cu" "F.Mask")
			(net 1 "GND")
			(pinfunction "GND")
			(pintype "passive")
		)
		(pad "D07" smd circle
			(at 17.144 1.904 90)
			(size 0.64 0.64)
			(layers "F.Cu" "F.Mask")
			(net 1 "GND")
			(pinfunction "GND")
			(pintype "passive")
		)
		(pad "D08" smd circle
			(at 15.874 1.904 90)
			(size 0.64 0.64)
			(layers "F.Cu" "F.Mask")
			(net 695 "/FMC+ HSPC/FMC.~{PERST}")
			(pinfunction "LA01_P_CC")
			(pintype "passive")
		)
		(pad "D09" smd circle
			(at 14.605 1.904 90)
			(size 0.64 0.64)
			(layers "F.Cu" "F.Mask")
			(net 100 "unconnected-(J18C-LA01_N_CC-PadD09)")
			(pinfunction "LA01_N_CC")
			(pintype "passive+no_connect")
		)
		(pad "D10" smd circle
			(at 13.335 1.904 90)
			(size 0.64 0.64)
			(layers "F.Cu" "F.Mask")
			(net 1 "GND")
			(pinfunction "GND")
			(pintype "passive")
		)
		(pad "D11" smd circle
			(at 12.063 1.904 90)
			(size 0.64 0.64)
			(layers "F.Cu" "F.Mask")
			(net 102 "unconnected-(J18C-LA05_P-PadD11)")
			(pinfunction "LA05_P")
			(pintype "passive+no_connect")
		)
		(pad "D12" smd circle
			(at 10.794 1.904 90)
			(size 0.64 0.64)
			(layers "F.Cu" "F.Mask")
			(net 103 "unconnected-(J18C-LA05_N-PadD12)")
			(pinfunction "LA05_N")
			(pintype "passive+no_connect")
		)
		(pad "D13" smd circle
			(at 9.525 1.904 90)
			(size 0.64 0.64)
			(layers "F.Cu" "F.Mask")
			(net 1 "GND")
			(pinfunction "GND")
			(pintype "passive")
		)
		(pad "D14" smd circle
			(at 8.255 1.904 90)
			(size 0.64 0.64)
			(layers "F.Cu" "F.Mask")
			(net 104 "unconnected-(J18C-LA09_P-PadD14)")
			(pinfunction "LA09_P")
			(pintype "passive+no_connect")
		)
		(pad "D15" smd circle
			(at 6.985 1.904 90)
			(size 0.64 0.64)
			(layers "F.Cu" "F.Mask")
			(net 106 "unconnected-(J18C-LA09_N-PadD15)")
			(pinfunction "LA09_N")
			(pintype "passive+no_connect")
		)
		(pad "D16" smd circle
			(at 5.714 1.904 90)
			(size 0.64 0.64)
			(layers "F.Cu" "F.Mask")
			(net 1 "GND")
			(pinfunction "GND")
			(pintype "passive")
		)
		(pad "D17" smd circle
			(at 4.445 1.904 90)
			(size 0.64 0.64)
			(layers "F.Cu" "F.Mask")
			(net 108 "unconnected-(J18C-LA13_P-PadD17)")
			(pinfunction "LA13_P")
			(pintype "passive+no_connect")
		)
		(pad "D18" smd circle
			(at 3.173 1.904 90)
			(size 0.64 0.64)
			(layers "F.Cu" "F.Mask")
			(net 110 "unconnected-(J18C-LA13_N-PadD18)")
			(pinfunction "LA13_N")
			(pintype "passive+no_connect")
		)
		(pad "D19" smd circle
			(at 1.904 1.904 90)
			(size 0.64 0.64)
			(layers "F.Cu" "F.Mask")
			(net 1 "GND")
			(pinfunction "GND")
			(pintype "passive")
		)
		(pad "D20" smd circle
			(at 0.633 1.904 90)
			(size 0.64 0.64)
			(layers "F.Cu" "F.Mask")
			(net 114 "unconnected-(J18C-LA17_P_CC-PadD20)")
			(pinfunction "LA17_P_CC")
			(pintype "passive+no_connect")
		)
		(pad "D21" smd circle
			(at -0.635 1.904 90)
			(size 0.64 0.64)
			(layers "F.Cu" "F.Mask")
			(net 116 "unconnected-(J18C-LA17_N_CC-PadD21)")
			(pinfunction "LA17_N_CC")
			(pintype "passive+no_connect")
		)
		(pad "D22" smd circle
			(at -1.905 1.904 90)
			(size 0.64 0.64)
			(layers "F.Cu" "F.Mask")
			(net 1 "GND")
			(pinfunction "GND")
			(pintype "passive")
		)
		(pad "D23" smd circle
			(at -3.176 1.904 90)
			(size 0.64 0.64)
			(layers "F.Cu" "F.Mask")
			(net 117 "unconnected-(J18C-LA23_P-PadD23)")
			(pinfunction "LA23_P")
			(pintype "passive+no_connect")
		)
		(pad "D24" smd circle
			(at -4.446 1.904 90)
			(size 0.64 0.64)
			(layers "F.Cu" "F.Mask")
			(net 118 "unconnected-(J18C-LA23_N-PadD24)")
			(pinfunction "LA23_N")
			(pintype "passive+no_connect")
		)
		(pad "D25" smd circle
			(at -5.715 1.904 90)
			(size 0.64 0.64)
			(layers "F.Cu" "F.Mask")
			(net 1 "GND")
			(pinfunction "GND")
			(pintype "passive")
		)
		(pad "D26" smd circle
			(at -6.986 1.904 90)
			(size 0.64 0.64)
			(layers "F.Cu" "F.Mask")
			(net 120 "unconnected-(J18C-LA26_P-PadD26)")
			(pinfunction "LA26_P")
			(pintype "passive+no_connect")
		)
		(pad "D27" smd circle
			(at -8.257 1.904 90)
			(size 0.64 0.64)
			(layers "F.Cu" "F.Mask")
			(net 121 "unconnected-(J18C-LA26_N-PadD27)")
			(pinfunction "LA26_N")
			(pintype "passive+no_connect")
		)
		(pad "D28" smd circle
			(at -9.526 1.904 90)
			(size 0.64 0.64)
			(layers "F.Cu" "F.Mask")
			(net 1 "GND")
			(pinfunction "GND")
			(pintype "passive")
		)
		(pad "D29" smd circle
			(at -10.795 1.904 90)
			(size 0.64 0.64)
			(layers "F.Cu" "F.Mask")
			(net 165 "/FPGA Config/JTAG.TCK")
			(pinfunction "TCK")
			(pintype "passive")
		)
		(pad "D30" smd circle
			(at -12.065 1.904 90)
			(size 0.64 0.64)
			(layers "F.Cu" "F.Mask")
			(net 220 "/FPGA Config/JTAG.TDI")
			(pinfunction "TDI")
			(pintype "passive")
		)
		(pad "D31" smd circle
			(at -13.337 1.904 90)
			(size 0.64 0.64)
			(layers "F.Cu" "F.Mask")
			(net 190 "/FPGA Config/JTAG.TDO")
			(pinfunction "TDO")
			(pintype "passive")
		)
		(pad "D32" smd circle
			(at -14.606 1.904 90)
			(size 0.64 0.64)
			(layers "F.Cu" "F.Mask")
			(net 125 "unconnected-(J18A-3P3VAUX-PadD32)")
			(pinfunction "3P3VAUX")
			(pintype "passive+no_connect")
		)
		(pad "D33" smd circle
			(at -15.875 1.904 90)
			(size 0.64 0.64)
			(layers "F.Cu" "F.Mask")
			(net 161 "/FPGA Config/JTAG.TMS")
			(pinfunction "TMS")
			(pintype "passive")
		)
		(pad "D34" smd circle
			(at -17.145 1.904 90)
			(size 0.64 0.64)
			(layers "F.Cu" "F.Mask")
			(net 431 "/FPGA Config/JTAG.RST")
			(pinfunction "TRST_L")
			(pintype "passive")
		)
		(pad "D35" smd circle
			(at -18.415 1.904 90)
			(size 0.64 0.64)
			(layers "F.Cu" "F.Mask")
			(net 126 "unconnected-(J18B-GA1-PadD35)")
			(pinfunction "GA1")
			(pintype "passive+no_connect")
		)
		(pad "D36" smd circle
			(at -19.685 1.904 90)
			(size 0.64 0.64)
			(layers "F.Cu" "F.Mask")
			(net 24 "+3V3")
			(pinfunction "3P3V")
			(pintype "passive")
		)
		(pad "D37" smd circle
			(at -20.956 1.904 90)
			(size 0.64 0.64)
			(layers "F.Cu" "F.Mask")
			(net 1 "GND")
			(pinfunction "GND")
			(pintype "passive")
		)
		(pad "D38" smd circle
			(at -22.226 1.904 90)
			(size 0.64 0.64)
			(layers "F.Cu" "F.Mask")
			(net 24 "+3V3")
			(pinfunction "3P3V")
			(pintype "passive")
		)
		(pad "D39" smd circle
			(at -23.497 1.904 90)
			(size 0.64 0.64)
			(layers "F.Cu" "F.Mask")
			(net 1 "GND")
			(pinfunction "GND")
			(pintype "passive")
		)
		(pad "D40" smd circle
			(at -24.767 1.904 90)
			(size 0.64 0.64)
			(layers "F.Cu" "F.Mask")
			(net 24 "+3V3")
			(pinfunction "3P3V")
			(pintype "passive")
		)
		(pad "E01" smd circle
			(at 24.765 0.633 90)
			(size 0.64 0.64)
			(layers "F.Cu" "F.Mask")
			(net 1 "GND")
			(pinfunction "GND")
			(pintype "passive")
		)
		(pad "E02" smd circle
			(at 23.495 0.633 90)
			(size 0.64 0.64)
			(layers "F.Cu" "F.Mask")
			(net 127 "unconnected-(J18D-HA01_P_CC-PadE02)")
			(pinfunction "HA01_P_CC")
			(pintype "passive+no_connect")
		)
		(pad "E03" smd circle
			(at 22.225 0.633 90)
			(size 0.64 0.64)
			(layers "F.Cu" "F.Mask")
			(net 128 "unconnected-(J18D-HA01_N_CC-PadE03)")
			(pinfunction "HA01_N_CC")
			(pintype "passive+no_connect")
		)
		(pad "E04" smd circle
			(at 20.954 0.633 90)
			(size 0.64 0.64)
			(layers "F.Cu" "F.Mask")
			(net 1 "GND")
			(pinfunction "GND")
			(pintype "passive")
		)
		(pad "E05" smd circle
			(at 19.684 0.633 90)
			(size 0.64 0.64)
			(layers "F.Cu" "F.Mask")
			(net 1 "GND")
			(pinfunction "GND")
			(pintype "passive")
		)
		(pad "E06" smd circle
			(at 18.414 0.633 90)
			(size 0.64 0.64)
			(layers "F.Cu" "F.Mask")
			(net 129 "unconnected-(J18D-HA05_P-PadE06)")
			(pinfunction "HA05_P")
			(pintype "passive+no_connect")
		)
		(pad "E07" smd circle
			(at 17.144 0.633 90)
			(size 0.64 0.64)
			(layers "F.Cu" "F.Mask")
			(net 130 "unconnected-(J18D-HA05_N-PadE07)")
			(pinfunction "HA05_N")
			(pintype "passive+no_connect")
		)
		(pad "E08" smd circle
			(at 15.874 0.633 90)
			(size 0.64 0.64)
			(layers "F.Cu" "F.Mask")
			(net 1 "GND")
			(pinfunction "GND")
			(pintype "passive")
		)
		(pad "E09" smd circle
			(at 14.605 0.633 90)
			(size 0.64 0.64)
			(layers "F.Cu" "F.Mask")
			(net 131 "unconnected-(J18D-HA09_P-PadE09)")
			(pinfunction "HA09_P")
			(pintype "passive+no_connect")
		)
		(pad "E10" smd circle
			(at 13.335 0.633 90)
			(size 0.64 0.64)
			(layers "F.Cu" "F.Mask")
			(net 132 "unconnected-(J18D-HA09_N-PadE10)")
			(pinfunction "HA09_N")
			(pintype "passive+no_connect")
		)
		(pad "E11" smd circle
			(at 12.063 0.633 90)
			(size 0.64 0.64)
			(layers "F.Cu" "F.Mask")
			(net 1 "GND")
			(pinfunction "GND")
			(pintype "passive")
		)
		(pad "E12" smd circle
			(at 10.794 0.633 90)
			(size 0.64 0.64)
			(layers "F.Cu" "F.Mask")
			(net 133 "unconnected-(J18D-HA13_P-PadE12)")
			(pinfunction "HA13_P")
			(pintype "passive+no_connect")
		)
		(pad "E13" smd circle
			(at 9.525 0.633 90)
			(size 0.64 0.64)
			(layers "F.Cu" "F.Mask")
			(net 134 "unconnected-(J18D-HA13_N-PadE13)")
			(pinfunction "HA13_N")
			(pintype "passive+no_connect")
		)
		(pad "E14" smd circle
			(at 8.255 0.633 90)
			(size 0.64 0.64)
			(layers "F.Cu" "F.Mask")
			(net 1 "GND")
			(pinfunction "GND")
			(pintype "passive")
		)
		(pad "E15" smd circle
			(at 6.985 0.633 90)
			(size 0.64 0.64)
			(layers "F.Cu" "F.Mask")
			(net 135 "unconnected-(J18D-HA16_P-PadE15)")
			(pinfunction "HA16_P")
			(pintype "passive+no_connect")
		)
		(pad "E16" smd circle
			(at 5.714 0.633 90)
			(size 0.64 0.64)
			(layers "F.Cu" "F.Mask")
			(net 136 "unconnected-(J18D-HA16_N-PadE16)")
			(pinfunction "HA16_N")
			(pintype "passive+no_connect")
		)
		(pad "E17" smd circle
			(at 4.445 0.633 90)
			(size 0.64 0.64)
			(layers "F.Cu" "F.Mask")
			(net 1 "GND")
			(pinfunction "GND")
			(pintype "passive")
		)
		(pad "E18" smd circle
			(at 3.173 0.633 90)
			(size 0.64 0.64)
			(layers "F.Cu" "F.Mask")
			(net 137 "unconnected-(J18D-HA20_P-PadE18)")
			(pinfunction "HA20_P")
			(pintype "passive+no_connect")
		)
	)
)
